FILE_TYPE = MULTI_PHYS_TABLE;

PART 'NB682GDZ'

{========================================================================================}
:VALUE       | PART_TYPE | MATERIAL | PART_NUMBER    = STANDARD    | LIFECYCLE     | PART_NUMBER   | JEDEC_TYPE  | DESCRIPTION                  | MANUFTR | MANUF_PN    | RD_CMPLS_LVL | CMPLS_LVL | FROM_PJ    | CLASS | DIP_SMD | DATA                | EE_CHECK_LIST | FP_ECN | PSL | CREATOR | STATUS | MSD  | ESD_CDM | ESD_HBM | ESD_MM | PIN_LENGTH_SHORT_PIN | PIN_LENGTH_LONG_PIN | CREATEDAY  ;
{========================================================================================}
 'NB682GD-Z' | 'SMLF'    | 'IC'     | 'AL000682001'(!) = ''               | ''               | 'AL000682001' |'QFN13_2X3'| 'IC CTRL(13P)NB682GD-Z(QFN)' | 'MPS'   | 'NB682GD-Z' | 'EP(V1)'     | ''        | 'S5T-GREG' | 'IC'  | ''      | 'MPS_NB682GD-Z.pdf' | ''            | ''     | ''  | ''      | ''     | 'NA' | 'NA'    | 'NA'    | 'NA'   | '0 MILS'             | '0 MILS'            | '20171019'
 'NB682GD-Z' | 'SMLF'    | 'EMPTY'  | 'AL000682001'(!) = ''               | ''               | 'AL000682001' |'QFN13_2X3'| 'IC CTRL(13P)NB682GD-Z(QFN)' | 'MPS'   | 'NB682GD-Z' | 'EP(V1)'     | ''        | 'S5T-GREG' | 'IC'  | ''      | 'MPS_NB682GD-Z.pdf' | ''            | ''     | ''  | ''      | ''     | 'NA' | 'NA'    | 'NA'    | 'NA'   | '0 MILS'             | '0 MILS'            | '20171019'

END_PART

END.

